# S9S_MB_2U (Grand Teton) — schematic netlist excerpt (pin names and nets, part order shuffled) for the footprints in the layout excerpt that follows; sources: Cadence DE-HDL packaged netlist, KiCad conversion of 03242023_DA0F0TMBIJ0_F0T_Motherboard_J_brd_V01_OCP.brd

Q79  MOSFET_NCH_DUAL  PJT138K IC  pkg SOT363XD  page 253
  S1  = GND
  G1  = PWRGD_PVCCD_HV_CPU0
  D2  = LED_PWRGD_PVPP_HBM_CPU0_D
  S2  = GND
  G2  = PWRGD_PVPP_HBM_CPU0
  D1  = LED_PWRGD_PVCCD_HV_CPU0_D

C764  Q_CAP_DIFFBUS  DIFF BUS_0.22UF 6.3V 20% X6S  pkg C0201  page 176 : \1\ = P5E_CPU1_PE2_TX_C_DN<4> ; \2\ = P5E_CPU1_PE2_TX_DN<4>
R2555  Q_RES  49.9 1% EMPTY  pkg 0402LF  page 284 : A = SVID_ALERT0_CPU1_R_N ; B = PVNN_TERM_CPU1

(kicad_pcb
	(version 20260206)
	(generator "pcbnew")
	(generator_version "10.0")
	(general
		(thickness 1.6)
		(legacy_teardrops no)
	)
	(paper "A4")
	(title_block
		(title "03242023_DA0F0TMBIJ0_F0T_Motherboard_J_brd_V01_OCP.brd")
		(comment 1 "Grand Teton / footprints 116-118 of 6105")
	)
	(layers
		(0 "F.Cu" signal "TOP")
		(4 "In1.Cu" signal "GND")
		(6 "In2.Cu" signal "IN1")
		(8 "In3.Cu" signal "GND1")
		(10 "In4.Cu" signal "IN2")
		(12 "In5.Cu" signal "GND2")
		(14 "In6.Cu" signal "IN3")
		(16 "In7.Cu" signal "GND3")
		(18 "In8.Cu" signal "VCC")
		(20 "In9.Cu" signal "VCC1")
		(22 "In10.Cu" signal "GND4")
		(24 "In11.Cu" signal "IN4")
		(26 "In12.Cu" signal "GND5")
		(28 "In13.Cu" signal "IN5")
		(30 "In14.Cu" signal "GND6")
		(32 "In15.Cu" signal "IN6")
		(34 "In16.Cu" signal "GND7")
		(2 "B.Cu" signal "BOTTOM")
		(9 "F.Adhes" user "F.Adhesive")
		(11 "B.Adhes" user "B.Adhesive")
		(13 "F.Paste" user "Package Geometry/Pastemask Top")
		(15 "B.Paste" user "Package Geometry/Pastemask Bottom")
		(5 "F.SilkS" user "Ref Des/Silkscreen Top")
		(7 "B.SilkS" user "Ref Des/Silkscreen Bottom")
		(1 "F.Mask" user "Board Geometry/Soldermask Top")
		(3 "B.Mask" user "Board Geometry/Soldermask Bottom")
		(17 "Dwgs.User" user "User.Drawings")
		(19 "Cmts.User" user "User.Comments")
		(21 "Eco1.User" user "User.Eco1")
		(23 "Eco2.User" user "User.Eco2")
		(25 "Edge.Cuts" user "Board Geometry/Outline")
		(27 "Margin" user)
		(31 "F.CrtYd" user "Package Geometry/Place Bound Top")
		(29 "B.CrtYd" user "Package Geometry/Place Bound Bottom")
		(35 "F.Fab" user "Ref Des/Assembly Top")
		(33 "B.Fab" user "Ref Des/Assembly Bottom")
	)
	(footprint ""
		(layer "F.Cu")
		(at 100.820728 -355.257862 180)
		(property "Reference" "R2555"
			(at 0 0 180)
			(layer "F.SilkS")
			(hide yes)
			(effects
				(font
					(size 1.27 1.27)
				)
			)
		)
		(property "Value" ""
			(at 0 0 180)
			(layer "F.Fab")
			(effects
				(font
					(size 1.27 1.27)
				)
			)
		)
		(duplicate_pad_numbers_are_jumpers no)
		(fp_line
			(start 0.7874 0.4064)
			(end -0.7874 0.4064)
			(stroke
				(width 0.1524)
				(type default)
			)
			(layer "F.SilkS")
		)
		(fp_line
			(start 0.7874 -0.4064)
			(end 0.7874 0.4064)
			(stroke
				(width 0.1524)
				(type default)
			)
			(layer "F.SilkS")
		)
		(fp_line
			(start -0.7874 0.4064)
			(end -0.7874 -0.4064)
			(stroke
				(width 0.1524)
				(type default)
			)
			(layer "F.SilkS")
		)
		(fp_line
			(start -0.7874 -0.4064)
			(end 0.7874 -0.4064)
			(stroke
				(width 0.1524)
				(type default)
			)
			(layer "F.SilkS")
		)
		(fp_line
			(start 0.67945 0.3048)
			(end 0.120396 0.3048)
			(stroke
				(width 0.1)
				(type default)
			)
			(layer "F.Fab")
		)
		(fp_line
			(start 0.67945 -0.3048)
			(end 0.67945 0.3048)
			(stroke
				(width 0.1)
				(type default)
			)
			(layer "F.Fab")
		)
		(fp_line
			(start 0.12065 -0.2794)
			(end 0.12065 -0.3048)
			(stroke
				(width 0.1)
				(type default)
			)
			(layer "F.Fab")
		)
		(fp_line
			(start 0.12065 -0.3048)
			(end 0.67945 -0.3048)
			(stroke
				(width 0.1)
				(type default)
			)
			(layer "F.Fab")
		)
		(fp_line
			(start 0.120396 0.3048)
			(end 0.120396 0.2794)
			(stroke
				(width 0.1)
				(type default)
			)
			(layer "F.Fab")
		)
		(fp_line
			(start 0.120396 0.2794)
			(end -0.12065 0.2794)
			(stroke
				(width 0.1)
				(type default)
			)
			(layer "F.Fab")
		)
		(fp_line
			(start -0.12065 0.3048)
			(end -0.67945 0.3048)
			(stroke
				(width 0.1)
				(type default)
			)
			(layer "F.Fab")
		)
		(fp_line
			(start -0.12065 0.2794)
			(end -0.12065 0.3048)
			(stroke
				(width 0.1)
				(type default)
			)
			(layer "F.Fab")
		)
		(fp_line
			(start -0.12065 -0.2794)
			(end 0.12065 -0.2794)
			(stroke
				(width 0.1)
				(type default)
			)
			(layer "F.Fab")
		)
		(fp_line
			(start -0.12065 -0.305054)
			(end -0.12065 -0.2794)
			(stroke
				(width 0.1)
				(type default)
			)
			(layer "F.Fab")
		)
		(fp_line
			(start -0.67945 0.3048)
			(end -0.67945 -0.305054)
			(stroke
				(width 0.1)
				(type default)
			)
			(layer "F.Fab")
		)
		(fp_line
			(start -0.67945 -0.305054)
			(end -0.12065 -0.305054)
			(stroke
				(width 0.1)
				(type default)
			)
			(layer "F.Fab")
		)
		(pad "1" smd circle
			(at -0.40005 0 180)
			(size 0 0)
			(layers "F.Cu" "F.Mask" "F.Paste")
			(net "SVID_ALERT0_CPU1_R_N")
		)
		(pad "2" smd circle
			(at 0.40005 0 180)
			(size 0 0)
			(layers "F.Cu" "F.Mask" "F.Paste")
			(net "PVNN_TERM_CPU1")
		)
	)
	(footprint ""
		(layer "F.Cu")
		(at 154.739594 -402.371052 -90)
		(property "Reference" "C764"
			(at 0 0 270)
			(layer "F.SilkS")
			(hide yes)
			(effects
				(font
					(size 1.27 1.27)
				)
			)
		)
		(property "Value" ""
			(at 0 0 270)
			(layer "F.Fab")
			(effects
				(font
					(size 1.27 1.27)
				)
			)
		)
		(duplicate_pad_numbers_are_jumpers no)
		(fp_line
			(start -0.299974 0.150114)
			(end -0.299974 -0.150114)
			(stroke
				(width 0.1)
				(type default)
			)
			(layer "F.Fab")
		)
		(fp_line
			(start 0.299974 0.150114)
			(end -0.299974 0.150114)
			(stroke
				(width 0.1)
				(type default)
			)
			(layer "F.Fab")
		)
		(fp_line
			(start -0.299974 -0.150114)
			(end 0.299974 -0.150114)
			(stroke
				(width 0.1)
				(type default)
			)
			(layer "F.Fab")
		)
		(fp_line
			(start 0.299974 -0.150114)
			(end 0.299974 0.150114)
			(stroke
				(width 0.1)
				(type default)
			)
			(layer "F.Fab")
		)
		(pad "1" smd rect
			(at -0.2667 0 270)
			(size 0.3048 0.381)
			(layers "F.Cu" "F.Mask" "F.Paste")
			(net "P5E_CPU1_PE2_TX_C_DN<4>")
		)
		(pad "2" smd rect
			(at 0.2667 0 270)
			(size 0.3048 0.381)
			(layers "F.Cu" "F.Mask" "F.Paste")
			(net "P5E_CPU1_PE2_TX_DN<4>")
		)
	)
	(footprint ""
		(layer "F.Cu")
		(at 100.936806 -102.693216)
		(property "Reference" "Q79"
			(at 1.7399 -0.815848 0)
			(unlocked yes)
			(layer "F.SilkS")
			(effects
				(font
					(size 0.7874 0.5842)
					(thickness 0.1524)
				)
				(justify left)
			)
		)
		(property "Value" ""
			(at 0 0 0)
			(layer "F.Fab")
			(effects
				(font
					(size 1.27 1.27)
				)
			)
		)
		(duplicate_pad_numbers_are_jumpers no)
		(fp_line
			(start -1.332738 -1.100074)
			(end -0.4826 -1.100074)
			(stroke
				(width 0.1524)
				(type default)
			)
			(layer "F.SilkS")
		)
		(fp_line
			(start -1.332738 1.100074)
			(end -1.332738 -1.100074)
			(stroke
				(width 0.1524)
				(type default)
			)
			(layer "F.SilkS")
		)
		(fp_line
			(start -0.4826 -1.100074)
			(end 0 -0.541274)
			(stroke
				(width 0.1524)
				(type default)
			)
			(layer "F.SilkS")
		)
		(fp_line
			(start 0 -0.541274)
			(end 0.4826 -1.100074)
			(stroke
				(width 0.1524)
				(type default)
			)
			(layer "F.SilkS")
		)
		(fp_line
			(start 0.4826 -1.100074)
			(end 1.332738 -1.100074)
			(stroke
				(width 0.1524)
				(type default)
			)
			(layer "F.SilkS")
		)
		(fp_line
			(start 1.332738 -1.100074)
			(end 1.332738 1.100074)
			(stroke
				(width 0.1524)
				(type default)
			)
			(layer "F.SilkS")
		)
		(fp_line
			(start 1.332738 1.100074)
			(end -1.332738 1.100074)
			(stroke
				(width 0.1524)
				(type default)
			)
			(layer "F.SilkS")
		)
		(fp_poly
			(pts
				(xy -0.603504 -1.950466) (xy -0.954532 -1.24841) (xy -1.30556 -1.950466)
			)
			(stroke
				(width 0)
				(type default)
			)
			(fill yes)
			(layer "F.SilkS")
		)
		(fp_line
			(start -0.674878 -1.100074)
			(end 0.674878 -1.100074)
			(stroke
				(width 0.1)
				(type default)
			)
			(layer "F.Fab")
		)
		(fp_line
			(start -0.674878 1.100074)
			(end -0.674878 -1.100074)
			(stroke
				(width 0.1)
				(type default)
			)
			(layer "F.Fab")
		)
		(fp_line
			(start 0.674878 -1.100074)
			(end 0.674878 1.100074)
			(stroke
				(width 0.1)
				(type default)
			)
			(layer "F.Fab")
		)
		(fp_line
			(start 0.674878 1.100074)
			(end -0.674878 1.100074)
			(stroke
				(width 0.1)
				(type default)
			)
			(layer "F.Fab")
		)
		(fp_poly
			(pts
				(xy -2.2352 -0.298958) (xy -2.2352 -1.001014) (xy -1.533144 -0.649986)
			)
			(stroke
				(width 0)
				(type default)
			)
			(fill yes)
			(layer "F.Fab")
		)
		(pad "1" smd rect
			(at -0.94996 -0.649986 90)
			(size 0.4318 0.508)
			(layers "F.Cu" "F.Mask" "F.Paste")
			(net "GND")
		)
		(pad "2" smd rect
			(at -0.94996 0 90)
			(size 0.4318 0.508)
			(layers "F.Cu" "F.Mask" "F.Paste")
			(net "PWRGD_PVCCD_HV_CPU0")
		)
		(pad "3" smd rect
			(at -0.94996 0.649986 90)
			(size 0.4318 0.508)
			(layers "F.Cu" "F.Mask" "F.Paste")
			(net "LED_PWRGD_PVPP_HBM_CPU0_D")
		)
		(pad "4" smd rect
			(at 0.94996 0.649986 90)
			(size 0.4318 0.508)
			(layers "F.Cu" "F.Mask" "F.Paste")
			(net "GND")
		)
		(pad "5" smd rect
			(at 0.94996 0 90)
			(size 0.4318 0.508)
			(layers "F.Cu" "F.Mask" "F.Paste")
			(net "PWRGD_PVPP_HBM_CPU0")
		)
		(pad "6" smd rect
			(at 0.94996 -0.649986 90)
			(size 0.4318 0.508)
			(layers "F.Cu" "F.Mask" "F.Paste")
			(net "LED_PWRGD_PVCCD_HV_CPU0_D")
		)
	)
)
